# SCM (Grand Teton) — schematic netlist excerpt (pin names and nets, part order shuffled) for the footprints in the layout excerpt that follows; sources: Cadence DE-HDL packaged netlist, KiCad conversion of 12092022_DA0F0TMDCD0_F0T_Management_Board_D_brd_V3_OCP.brd

L2  Q_INDUCTOR  BLM18PG121SN1D/2000MA IND  pkg SMLF  page 17 : \1\ = P1V2_AUX ; \2\ = P3V3_STBY_PLLAHVDD
L11  Q_INDUCTOR  BLM18PG121SN1D/2000MA IND  pkg SMLF  page 16 : \1\ = P1V2_AUX ; \2\ = P1V2_STBY_MVDD_CK

(kicad_pcb
	(version 20260206)
	(generator "pcbnew")
	(generator_version "10.0")
	(general
		(thickness 1.6)
		(legacy_teardrops no)
	)
	(paper "A4")
	(title_block
		(title "12092022_DA0F0TMDCD0_F0T_Management_Board_D_brd_V3_OCP.brd")
		(comment 1 "Grand Teton / footprints 1177-1178 of 1440")
	)
	(layers
		(0 "F.Cu" signal "TOP")
		(4 "In1.Cu" signal "GND")
		(6 "In2.Cu" signal "IN1")
		(8 "In3.Cu" signal "GND1")
		(10 "In4.Cu" signal "IN2")
		(12 "In5.Cu" signal "VCC")
		(14 "In6.Cu" signal "VCC1")
		(16 "In7.Cu" signal "IN3")
		(18 "In8.Cu" signal "GND2")
		(20 "In9.Cu" signal "IN4")
		(22 "In10.Cu" signal "GND3")
		(2 "B.Cu" signal "BOTTOM")
		(9 "F.Adhes" user "F.Adhesive")
		(11 "B.Adhes" user "B.Adhesive")
		(13 "F.Paste" user "Package Geometry/Pastemask Top")
		(15 "B.Paste" user "Package Geometry/Pastemask Bottom")
		(5 "F.SilkS" user "Ref Des/Silkscreen Top")
		(7 "B.SilkS" user "Ref Des/Silkscreen Bottom")
		(1 "F.Mask" user "Board Geometry/Soldermask Top")
		(3 "B.Mask" user "Board Geometry/Soldermask Bottom")
		(17 "Dwgs.User" user "User.Drawings")
		(19 "Cmts.User" user "User.Comments")
		(21 "Eco1.User" user "User.Eco1")
		(23 "Eco2.User" user "User.Eco2")
		(25 "Edge.Cuts" user "Board Geometry/Outline")
		(27 "Margin" user)
		(31 "F.CrtYd" user "Package Geometry/Place Bound Top")
		(29 "B.CrtYd" user "Package Geometry/Place Bound Bottom")
		(35 "F.Fab" user "Ref Des/Assembly Top")
		(33 "B.Fab" user "Ref Des/Assembly Bottom")
	)
	(footprint ""
		(layer "B.Cu")
		(at 36.957 -32.766)
		(property "Reference" "L2"
			(at 0 0 0)
			(layer "B.SilkS")
			(hide yes)
			(effects
				(font
					(size 1.27 1.27)
				)
				(justify mirror)
			)
		)
		(property "Value" ""
			(at 0 0 0)
			(layer "B.Fab")
			(effects
				(font
					(size 1.27 1.27)
				)
				(justify mirror)
			)
		)
		(duplicate_pad_numbers_are_jumpers no)
		(fp_line
			(start -1.27 0.5842)
			(end -1.27 -0.5842)
			(stroke
				(width 0.1524)
				(type default)
			)
			(layer "B.SilkS")
		)
		(fp_line
			(start -1.27 0.5842)
			(end 1.27 0.5842)
			(stroke
				(width 0.1524)
				(type default)
			)
			(layer "B.SilkS")
		)
		(fp_line
			(start -0.127 0.5842)
			(end -0.127 -0.5842)
			(stroke
				(width 0.1524)
				(type default)
			)
			(layer "B.SilkS")
		)
		(fp_line
			(start 0.127 0.5842)
			(end 0.127 -0.5842)
			(stroke
				(width 0.1524)
				(type default)
			)
			(layer "B.SilkS")
		)
		(fp_line
			(start 1.27 -0.5842)
			(end -1.27 -0.5842)
			(stroke
				(width 0.1524)
				(type default)
			)
			(layer "B.SilkS")
		)
		(fp_line
			(start 1.27 -0.5588)
			(end 1.27 -0.5842)
			(stroke
				(width 0.1524)
				(type default)
			)
			(layer "B.SilkS")
		)
		(fp_line
			(start 1.27 0.5842)
			(end 1.27 -0.5842)
			(stroke
				(width 0.1524)
				(type default)
			)
			(layer "B.SilkS")
		)
		(fp_line
			(start -1.1938 -0.406654)
			(end -1.1938 0.4064)
			(stroke
				(width 0.1)
				(type default)
			)
			(layer "B.Fab")
		)
		(fp_line
			(start -1.1938 0.4064)
			(end -0.9144 0.4064)
			(stroke
				(width 0.1)
				(type default)
			)
			(layer "B.Fab")
		)
		(fp_line
			(start -0.9144 -0.508)
			(end -0.9144 -0.406654)
			(stroke
				(width 0.1)
				(type default)
			)
			(layer "B.Fab")
		)
		(fp_line
			(start -0.9144 -0.406654)
			(end -1.1938 -0.406654)
			(stroke
				(width 0.1)
				(type default)
			)
			(layer "B.Fab")
		)
		(fp_line
			(start -0.9144 0.4064)
			(end -0.9144 0.508)
			(stroke
				(width 0.1)
				(type default)
			)
			(layer "B.Fab")
		)
		(fp_line
			(start -0.9144 0.508)
			(end 0.9144 0.508)
			(stroke
				(width 0.1)
				(type default)
			)
			(layer "B.Fab")
		)
		(fp_line
			(start 0.9144 -0.508)
			(end -0.9144 -0.508)
			(stroke
				(width 0.1)
				(type default)
			)
			(layer "B.Fab")
		)
		(fp_line
			(start 0.9144 -0.406654)
			(end 0.9144 -0.508)
			(stroke
				(width 0.1)
				(type default)
			)
			(layer "B.Fab")
		)
		(fp_line
			(start 0.9144 0.406654)
			(end 1.194308 0.406654)
			(stroke
				(width 0.1)
				(type default)
			)
			(layer "B.Fab")
		)
		(fp_line
			(start 0.9144 0.508)
			(end 0.9144 0.406654)
			(stroke
				(width 0.1)
				(type default)
			)
			(layer "B.Fab")
		)
		(fp_line
			(start 1.194308 -0.406654)
			(end 0.9144 -0.406654)
			(stroke
				(width 0.1)
				(type default)
			)
			(layer "B.Fab")
		)
		(fp_line
			(start 1.194308 0.406654)
			(end 1.194308 -0.406654)
			(stroke
				(width 0.1)
				(type default)
			)
			(layer "B.Fab")
		)
		(pad "1" smd rect
			(at 0.7366 0 270)
			(size 0.7112 0.8128)
			(layers "B.Cu" "B.Mask" "B.Paste")
			(net "P1V2_AUX")
		)
		(pad "2" smd rect
			(at -0.7366 0 270)
			(size 0.7112 0.8128)
			(layers "B.Cu" "B.Mask" "B.Paste")
			(net "P3V3_STBY_PLLAHVDD")
		)
	)
	(footprint ""
		(layer "B.Cu")
		(at 69.342 -43.307)
		(property "Reference" "L11"
			(at 0 0 0)
			(layer "B.SilkS")
			(hide yes)
			(effects
				(font
					(size 1.27 1.27)
				)
				(justify mirror)
			)
		)
		(property "Value" ""
			(at 0 0 0)
			(layer "B.Fab")
			(effects
				(font
					(size 1.27 1.27)
				)
				(justify mirror)
			)
		)
		(duplicate_pad_numbers_are_jumpers no)
		(fp_line
			(start -1.27 0.5842)
			(end -1.27 -0.5842)
			(stroke
				(width 0.1524)
				(type default)
			)
			(layer "B.SilkS")
		)
		(fp_line
			(start -1.27 0.5842)
			(end 1.27 0.5842)
			(stroke
				(width 0.1524)
				(type default)
			)
			(layer "B.SilkS")
		)
		(fp_line
			(start -0.127 0.5842)
			(end -0.127 -0.5842)
			(stroke
				(width 0.1524)
				(type default)
			)
			(layer "B.SilkS")
		)
		(fp_line
			(start 0.127 0.5842)
			(end 0.127 -0.5842)
			(stroke
				(width 0.1524)
				(type default)
			)
			(layer "B.SilkS")
		)
		(fp_line
			(start 1.27 -0.5842)
			(end -1.27 -0.5842)
			(stroke
				(width 0.1524)
				(type default)
			)
			(layer "B.SilkS")
		)
		(fp_line
			(start 1.27 -0.5588)
			(end 1.27 -0.5842)
			(stroke
				(width 0.1524)
				(type default)
			)
			(layer "B.SilkS")
		)
		(fp_line
			(start 1.27 0.5842)
			(end 1.27 -0.5842)
			(stroke
				(width 0.1524)
				(type default)
			)
			(layer "B.SilkS")
		)
		(fp_line
			(start -1.1938 -0.406654)
			(end -1.1938 0.4064)
			(stroke
				(width 0.1)
				(type default)
			)
			(layer "B.Fab")
		)
		(fp_line
			(start -1.1938 0.4064)
			(end -0.9144 0.4064)
			(stroke
				(width 0.1)
				(type default)
			)
			(layer "B.Fab")
		)
		(fp_line
			(start -0.9144 -0.508)
			(end -0.9144 -0.406654)
			(stroke
				(width 0.1)
				(type default)
			)
			(layer "B.Fab")
		)
		(fp_line
			(start -0.9144 -0.406654)
			(end -1.1938 -0.406654)
			(stroke
				(width 0.1)
				(type default)
			)
			(layer "B.Fab")
		)
		(fp_line
			(start -0.9144 0.4064)
			(end -0.9144 0.508)
			(stroke
				(width 0.1)
				(type default)
			)
			(layer "B.Fab")
		)
		(fp_line
			(start -0.9144 0.508)
			(end 0.9144 0.508)
			(stroke
				(width 0.1)
				(type default)
			)
			(layer "B.Fab")
		)
		(fp_line
			(start 0.9144 -0.508)
			(end -0.9144 -0.508)
			(stroke
				(width 0.1)
				(type default)
			)
			(layer "B.Fab")
		)
		(fp_line
			(start 0.9144 -0.406654)
			(end 0.9144 -0.508)
			(stroke
				(width 0.1)
				(type default)
			)
			(layer "B.Fab")
		)
		(fp_line
			(start 0.9144 0.406654)
			(end 1.194308 0.406654)
			(stroke
				(width 0.1)
				(type default)
			)
			(layer "B.Fab")
		)
		(fp_line
			(start 0.9144 0.508)
			(end 0.9144 0.406654)
			(stroke
				(width 0.1)
				(type default)
			)
			(layer "B.Fab")
		)
		(fp_line
			(start 1.194308 -0.406654)
			(end 0.9144 -0.406654)
			(stroke
				(width 0.1)
				(type default)
			)
			(layer "B.Fab")
		)
		(fp_line
			(start 1.194308 0.406654)
			(end 1.194308 -0.406654)
			(stroke
				(width 0.1)
				(type default)
			)
			(layer "B.Fab")
		)
		(pad "1" smd rect
			(at 0.7366 0 270)
			(size 0.7112 0.8128)
			(layers "B.Cu" "B.Mask" "B.Paste")
			(net "P1V2_AUX")
		)
		(pad "2" smd rect
			(at -0.7366 0 270)
			(size 0.7112 0.8128)
			(layers "B.Cu" "B.Mask" "B.Paste")
			(net "P1V2_STBY_MVDD_CK")
		)
	)
)
